# T6G (Grand Teton) — schematic netlist excerpt (pin names and nets, part order shuffled) for the footprints in the layout excerpt that follows; sources: Cadence DE-HDL packaged netlist, KiCad conversion of 04192023_DAF0TMB3IC0_F0TG_MB_C_brd_V02_OCP.brd

PR318  Q_RES  2.2 1% CHIP  pkg 0402LF  page 194 : A = PVDDCR_CPU0_P0_PVCC ; B = PVDDCR_CPU0_P0_VCC1
C403  Q_CAP  0.1UF 10V 10% X7S  pkg C0201  page 345 : A = P0V9_CPU1_RT2_2A ; B = GND
PC572_5  Q_CAP  22UF 16V 20% X6S  pkg C0805  page 196 : A = SW_P12V_AUX_PVDDCR_CPU0_P0_FLT ; B = GND
PC633_4  Q_CAP  22UF 16V 20% X6S  pkg C0805  page 223 : A = SW_P12V_AUX_PVDDIO_P1_FLT ; B = GND

(kicad_pcb
	(version 20260206)
	(generator "pcbnew")
	(generator_version "10.0")
	(general
		(thickness 1.6)
		(legacy_teardrops no)
	)
	(paper "A4")
	(title_block
		(title "04192023_DAF0TMB3IC0_F0TG_MB_C_brd_V02_OCP.brd")
		(comment 1 "Grand Teton / footprints 7010-7013 of 8354")
	)
	(layers
		(0 "F.Cu" signal "TOP")
		(4 "In1.Cu" signal "GND")
		(6 "In2.Cu" signal "IN1")
		(8 "In3.Cu" signal "GND1")
		(10 "In4.Cu" signal "IN2")
		(12 "In5.Cu" signal "GND2")
		(14 "In6.Cu" signal "IN3")
		(16 "In7.Cu" signal "GND3")
		(18 "In8.Cu" signal "VCC")
		(20 "In9.Cu" signal "VCC1")
		(22 "In10.Cu" signal "GND4")
		(24 "In11.Cu" signal "IN4")
		(26 "In12.Cu" signal "GND5")
		(28 "In13.Cu" signal "IN5")
		(30 "In14.Cu" signal "GND6")
		(32 "In15.Cu" signal "IN6")
		(34 "In16.Cu" signal "GND7")
		(2 "B.Cu" signal "BOTTOM")
		(9 "F.Adhes" user "F.Adhesive")
		(11 "B.Adhes" user "B.Adhesive")
		(13 "F.Paste" user "Package Geometry/Pastemask Top")
		(15 "B.Paste" user "Package Geometry/Pastemask Bottom")
		(5 "F.SilkS" user "Ref Des/Silkscreen Top")
		(7 "B.SilkS" user "Ref Des/Silkscreen Bottom")
		(1 "F.Mask" user "Board Geometry/Soldermask Top")
		(3 "B.Mask" user "Board Geometry/Soldermask Bottom")
		(17 "Dwgs.User" user "User.Drawings")
		(19 "Cmts.User" user "User.Comments")
		(21 "Eco1.User" user "User.Eco1")
		(23 "Eco2.User" user "User.Eco2")
		(25 "Edge.Cuts" user "Board Geometry/Outline")
		(27 "Margin" user)
		(31 "F.CrtYd" user "Package Geometry/Place Bound Top")
		(29 "B.CrtYd" user "Package Geometry/Place Bound Bottom")
		(35 "F.Fab" user "Ref Des/Assembly Top")
		(33 "B.Fab" user "Ref Des/Assembly Bottom")
	)
	(footprint ""
		(layer "B.Cu")
		(at 29.722318 -346.788994 90)
		(property "Reference" "PC633_4"
			(at 0 0 90)
			(layer "B.SilkS")
			(hide yes)
			(effects
				(font
					(size 1.27 1.27)
				)
				(justify mirror)
			)
		)
		(property "Value" ""
			(at 0 0 90)
			(layer "B.Fab")
			(effects
				(font
					(size 1.27 1.27)
				)
				(justify mirror)
			)
		)
		(duplicate_pad_numbers_are_jumpers no)
		(fp_line
			(start 1.524 -0.762)
			(end -1.524 -0.762)
			(stroke
				(width 0.1524)
				(type default)
			)
			(layer "B.SilkS")
		)
		(fp_line
			(start -1.524 -0.762)
			(end -1.524 0.762)
			(stroke
				(width 0.1524)
				(type default)
			)
			(layer "B.SilkS")
		)
		(fp_line
			(start 1.524 0.762)
			(end 1.524 -0.762)
			(stroke
				(width 0.1524)
				(type default)
			)
			(layer "B.SilkS")
		)
		(fp_line
			(start -1.524 0.762)
			(end 1.524 0.762)
			(stroke
				(width 0.1524)
				(type default)
			)
			(layer "B.SilkS")
		)
		(fp_line
			(start 1.1049 -0.724916)
			(end 1.1049 0.724916)
			(stroke
				(width 0.1)
				(type default)
			)
			(layer "B.Fab")
		)
		(fp_line
			(start -1.1049 -0.724916)
			(end 1.1049 -0.724916)
			(stroke
				(width 0.1)
				(type default)
			)
			(layer "B.Fab")
		)
		(fp_line
			(start 1.1049 0.724916)
			(end -1.1049 0.724916)
			(stroke
				(width 0.1)
				(type default)
			)
			(layer "B.Fab")
		)
		(fp_line
			(start -1.1049 0.724916)
			(end -1.1049 -0.724916)
			(stroke
				(width 0.1)
				(type default)
			)
			(layer "B.Fab")
		)
		(pad "1" smd rect
			(at 0.889 0 90)
			(size 1.016 1.27)
			(layers "B.Cu" "B.Mask" "B.Paste")
			(net "SW_P12V_AUX_PVDDIO_P1_FLT")
		)
		(pad "2" smd rect
			(at -0.889 0 90)
			(size 1.016 1.27)
			(layers "B.Cu" "B.Mask" "B.Paste")
			(net "GND")
		)
	)
	(footprint ""
		(layer "B.Cu")
		(at 366.62487 -176.712118 90)
		(property "Reference" "PR318"
			(at 0 0 90)
			(layer "B.SilkS")
			(hide yes)
			(effects
				(font
					(size 1.27 1.27)
				)
				(justify mirror)
			)
		)
		(property "Value" ""
			(at 0 0 90)
			(layer "B.Fab")
			(effects
				(font
					(size 1.27 1.27)
				)
				(justify mirror)
			)
		)
		(duplicate_pad_numbers_are_jumpers no)
		(fp_line
			(start 0.7874 -0.4064)
			(end -0.7874 -0.4064)
			(stroke
				(width 0.1524)
				(type default)
			)
			(layer "B.SilkS")
		)
		(fp_line
			(start -0.7874 -0.4064)
			(end -0.7874 0.4064)
			(stroke
				(width 0.1524)
				(type default)
			)
			(layer "B.SilkS")
		)
		(fp_line
			(start 0.7874 0.4064)
			(end 0.7874 -0.4064)
			(stroke
				(width 0.1524)
				(type default)
			)
			(layer "B.SilkS")
		)
		(fp_line
			(start -0.7874 0.4064)
			(end 0.7874 0.4064)
			(stroke
				(width 0.1524)
				(type default)
			)
			(layer "B.SilkS")
		)
		(fp_line
			(start 0.67945 -0.305054)
			(end 0.12065 -0.305054)
			(stroke
				(width 0.1)
				(type default)
			)
			(layer "B.Fab")
		)
		(fp_line
			(start 0.12065 -0.305054)
			(end 0.12065 -0.2794)
			(stroke
				(width 0.1)
				(type default)
			)
			(layer "B.Fab")
		)
		(fp_line
			(start -0.12065 -0.3048)
			(end -0.67945 -0.3048)
			(stroke
				(width 0.1)
				(type default)
			)
			(layer "B.Fab")
		)
		(fp_line
			(start -0.67945 -0.3048)
			(end -0.67945 0.3048)
			(stroke
				(width 0.1)
				(type default)
			)
			(layer "B.Fab")
		)
		(fp_line
			(start 0.12065 -0.2794)
			(end -0.12065 -0.2794)
			(stroke
				(width 0.1)
				(type default)
			)
			(layer "B.Fab")
		)
		(fp_line
			(start -0.12065 -0.2794)
			(end -0.12065 -0.3048)
			(stroke
				(width 0.1)
				(type default)
			)
			(layer "B.Fab")
		)
		(fp_line
			(start 0.12065 0.2794)
			(end 0.12065 0.3048)
			(stroke
				(width 0.1)
				(type default)
			)
			(layer "B.Fab")
		)
		(fp_line
			(start -0.120396 0.2794)
			(end 0.12065 0.2794)
			(stroke
				(width 0.1)
				(type default)
			)
			(layer "B.Fab")
		)
		(fp_line
			(start 0.67945 0.3048)
			(end 0.67945 -0.305054)
			(stroke
				(width 0.1)
				(type default)
			)
			(layer "B.Fab")
		)
		(fp_line
			(start 0.12065 0.3048)
			(end 0.67945 0.3048)
			(stroke
				(width 0.1)
				(type default)
			)
			(layer "B.Fab")
		)
		(fp_line
			(start -0.120396 0.3048)
			(end -0.120396 0.2794)
			(stroke
				(width 0.1)
				(type default)
			)
			(layer "B.Fab")
		)
		(fp_line
			(start -0.67945 0.3048)
			(end -0.120396 0.3048)
			(stroke
				(width 0.1)
				(type default)
			)
			(layer "B.Fab")
		)
		(pad "1" smd circle
			(at 0.40005 0 270)
			(size 0 0)
			(layers "B.Cu" "B.Mask" "B.Paste")
			(net "PVDDCR_CPU0_P0_PVCC")
		)
		(pad "2" smd circle
			(at -0.40005 0 270)
			(size 0 0)
			(layers "B.Cu" "B.Mask" "B.Paste")
			(net "PVDDCR_CPU0_P0_VCC1")
		)
	)
	(footprint ""
		(layer "B.Cu")
		(at 150.746206 -388.011162 -90)
		(property "Reference" "C403"
			(at 0 0 90)
			(layer "B.SilkS")
			(hide yes)
			(effects
				(font
					(size 1.27 1.27)
				)
				(justify mirror)
			)
		)
		(property "Value" ""
			(at 0 0 90)
			(layer "B.Fab")
			(effects
				(font
					(size 1.27 1.27)
				)
				(justify mirror)
			)
		)
		(duplicate_pad_numbers_are_jumpers no)
		(fp_line
			(start -0.299974 0.150114)
			(end 0.299974 0.150114)
			(stroke
				(width 0.1)
				(type default)
			)
			(layer "B.Fab")
		)
		(fp_line
			(start 0.299974 0.150114)
			(end 0.299974 -0.150114)
			(stroke
				(width 0.1)
				(type default)
			)
			(layer "B.Fab")
		)
		(fp_line
			(start -0.299974 -0.150114)
			(end -0.299974 0.150114)
			(stroke
				(width 0.1)
				(type default)
			)
			(layer "B.Fab")
		)
		(fp_line
			(start 0.299974 -0.150114)
			(end -0.299974 -0.150114)
			(stroke
				(width 0.1)
				(type default)
			)
			(layer "B.Fab")
		)
		(pad "1" smd rect
			(at 0.2667 0 90)
			(size 0.3048 0.381)
			(layers "B.Cu" "B.Mask" "B.Paste")
			(net "P0V9_CPU1_RT2_2A")
		)
		(pad "2" smd rect
			(at -0.2667 0 90)
			(size 0.3048 0.381)
			(layers "B.Cu" "B.Mask" "B.Paste")
			(net "GND")
		)
	)
	(footprint ""
		(layer "B.Cu")
		(at 352.974656 -169.619676 -90)
		(property "Reference" "PC572_5"
			(at 0 0 90)
			(layer "B.SilkS")
			(hide yes)
			(effects
				(font
					(size 1.27 1.27)
				)
				(justify mirror)
			)
		)
		(property "Value" ""
			(at 0 0 90)
			(layer "B.Fab")
			(effects
				(font
					(size 1.27 1.27)
				)
				(justify mirror)
			)
		)
		(duplicate_pad_numbers_are_jumpers no)
		(fp_line
			(start -1.524 0.762)
			(end 1.524 0.762)
			(stroke
				(width 0.1524)
				(type default)
			)
			(layer "B.SilkS")
		)
		(fp_line
			(start 1.524 0.762)
			(end 1.524 -0.762)
			(stroke
				(width 0.1524)
				(type default)
			)
			(layer "B.SilkS")
		)
		(fp_line
			(start -1.524 -0.762)
			(end -1.524 0.762)
			(stroke
				(width 0.1524)
				(type default)
			)
			(layer "B.SilkS")
		)
		(fp_line
			(start 1.524 -0.762)
			(end -1.524 -0.762)
			(stroke
				(width 0.1524)
				(type default)
			)
			(layer "B.SilkS")
		)
		(fp_line
			(start -1.1049 0.724916)
			(end -1.1049 -0.724916)
			(stroke
				(width 0.1)
				(type default)
			)
			(layer "B.Fab")
		)
		(fp_line
			(start 1.1049 0.724916)
			(end -1.1049 0.724916)
			(stroke
				(width 0.1)
				(type default)
			)
			(layer "B.Fab")
		)
		(fp_line
			(start -1.1049 -0.724916)
			(end 1.1049 -0.724916)
			(stroke
				(width 0.1)
				(type default)
			)
			(layer "B.Fab")
		)
		(fp_line
			(start 1.1049 -0.724916)
			(end 1.1049 0.724916)
			(stroke
				(width 0.1)
				(type default)
			)
			(layer "B.Fab")
		)
		(pad "1" smd rect
			(at 0.889 0 270)
			(size 1.016 1.27)
			(layers "B.Cu" "B.Mask" "B.Paste")
			(net "SW_P12V_AUX_PVDDCR_CPU0_P0_FLT")
		)
		(pad "2" smd rect
			(at -0.889 0 270)
			(size 1.016 1.27)
			(layers "B.Cu" "B.Mask" "B.Paste")
			(net "GND")
		)
	)
)
